(kicad_pcb
	(version 20260206)
	(generator "pcbnew")
	(generator_version "10.0")
	(general
		(thickness 1.6)
		(legacy_teardrops no)
	)
	(paper "A4")
	(title_block
		(title "panther-plus-userver — 13130-1b_20150205.brd")
		(comment 1 "Honey Badger (Wiwynn) / footprints 1305-1311 of 1509")
	)
	(layers
		(0 "F.Cu" signal "TOP")
		(4 "In1.Cu" signal "L2")
		(6 "In2.Cu" signal "L3")
		(8 "In3.Cu" signal "L4")
		(10 "In4.Cu" signal "L5")
		(12 "In5.Cu" signal "L6")
		(14 "In6.Cu" signal "L7")
		(16 "In7.Cu" signal "L8")
		(18 "In8.Cu" signal "L9")
		(20 "In9.Cu" signal "L10")
		(22 "In10.Cu" signal "L11")
		(2 "B.Cu" signal "BOTTOM")
		(9 "F.Adhes" user "F.Adhesive")
		(11 "B.Adhes" user "B.Adhesive")
		(13 "F.Paste" user "Package Geometry/Pastemask Top")
		(15 "B.Paste" user "Package Geometry/Pastemask Bottom")
		(5 "F.SilkS" user "Ref Des/Silkscreen Top")
		(7 "B.SilkS" user "Ref Des/Silkscreen Bottom")
		(1 "F.Mask" user "Board Geometry/Soldermask Top")
		(3 "B.Mask" user "Board Geometry/Soldermask Bottom")
		(17 "Dwgs.User" user "User.Drawings")
		(19 "Cmts.User" user "User.Comments")
		(21 "Eco1.User" user "User.Eco1")
		(23 "Eco2.User" user "User.Eco2")
		(25 "Edge.Cuts" user "Board Geometry/Outline")
		(27 "Margin" user)
		(31 "F.CrtYd" user "Package Geometry/Place Bound Top")
		(29 "B.CrtYd" user "Package Geometry/Place Bound Bottom")
		(35 "F.Fab" user "Ref Des/Assembly Top")
		(33 "B.Fab" user "Ref Des/Assembly Bottom")
	)
	(footprint ""
		(layer "B.Cu")
		(at 105.283 -15.875)
		(property "Reference" "R466"
			(at 0 0 0)
			(layer "B.SilkS")
			(hide yes)
			(effects
				(font
					(size 1.27 1.27)
				)
				(justify mirror)
			)
		)
		(property "Value" "4K7R2F-GP"
			(at -1.7907 -1.1176 0)
			(unlocked yes)
			(layer "B.Fab")
			(hide yes)
			(effects
				(font
					(size 1.016 1.016)
					(thickness 0.1524)
				)
				(justify mirror)
			)
		)
		(property "Device Type" "R402H16"
			(at -1.7907 -2.6416 0)
			(unlocked yes)
			(layer "B.Fab")
			(hide yes)
			(effects
				(font
					(size 1.016 1.016)
					(thickness 0.1524)
				)
				(justify mirror)
			)
		)
		(duplicate_pad_numbers_are_jumpers no)
		(fp_rect
			(start 0.381 0.8382)
			(end -0.381 -0.8382)
			(stroke
				(width 0)
				(type default)
			)
			(fill no)
			(layer "B.CrtYd")
		)
		(fp_rect
			(start 0.381 0.8382)
			(end -0.381 -0.8382)
			(stroke
				(width 0)
				(type default)
			)
			(fill no)
			(layer "B.Fab")
		)
		(pad "1" smd custom
			(at 0 -0.4318 180)
			(size 0.127 0.127)
			(layers "B.Cu" "B.Mask" "B.Paste")
			(net "P3V3_STBY")
			(options
				(clearance outline)
				(anchor circle)
			)
			(primitives
				(gr_poly
					(pts
						(arc
							(start -0.2032 0.2794)
							(mid -0.239121 0.264521)
							(end -0.254 0.2286)
						)
						(arc
							(start -0.254 -0.2286)
							(mid -0.239121 -0.264521)
							(end -0.2032 -0.2794)
						)
						(arc
							(start 0.2032 -0.2794)
							(mid 0.239121 -0.264521)
							(end 0.254 -0.2286)
						)
						(arc
							(start 0.254 0.2286)
							(mid 0.239121 0.264521)
							(end 0.2032 0.2794)
						)
					)
					(width 0)
					(fill yes)
				)
			)
		)
		(pad "2" smd custom
			(at 0 0.4318 180)
			(size 0.127 0.127)
			(layers "B.Cu" "B.Mask" "B.Paste")
			(net "IRQ_CPU_LV_IERR#")
			(options
				(clearance outline)
				(anchor circle)
			)
			(primitives
				(gr_poly
					(pts
						(arc
							(start -0.2032 0.2794)
							(mid -0.239121 0.264521)
							(end -0.254 0.2286)
						)
						(arc
							(start -0.254 -0.2286)
							(mid -0.239121 -0.264521)
							(end -0.2032 -0.2794)
						)
						(arc
							(start 0.2032 -0.2794)
							(mid 0.239121 -0.264521)
							(end 0.254 -0.2286)
						)
						(arc
							(start 0.254 0.2286)
							(mid 0.239121 0.264521)
							(end 0.2032 0.2794)
						)
					)
					(width 0)
					(fill yes)
				)
			)
		)
	)
	(footprint ""
		(layer "B.Cu")
		(at 201.295 -42.6466 90)
		(property "Reference" "LED12"
			(at 0 0 90)
			(layer "B.SilkS")
			(hide yes)
			(effects
				(font
					(size 1.27 1.27)
				)
				(justify mirror)
			)
		)
		(property "Value" "LED-YG-51-GP"
			(at 0.0381 -2.6162 90)
			(unlocked yes)
			(layer "B.Fab")
			(hide yes)
			(effects
				(font
					(size 1.016 1.016)
					(thickness 0.1524)
				)
				(justify mirror)
			)
		)
		(property "Device Type" "LED1608AKH40"
			(at 0.0381 -4.1402 90)
			(unlocked yes)
			(layer "B.Fab")
			(hide yes)
			(effects
				(font
					(size 1.016 1.016)
					(thickness 0.1524)
				)
				(justify mirror)
			)
		)
		(duplicate_pad_numbers_are_jumpers no)
		(fp_line
			(start 0.5334 1.3081)
			(end -0.5334 1.3081)
			(stroke
				(width 0.254)
				(type default)
			)
			(layer "B.SilkS")
		)
		(fp_rect
			(start 0.6604 1.1811)
			(end -0.6604 -1.1811)
			(stroke
				(width 0)
				(type default)
			)
			(fill no)
			(layer "B.CrtYd")
		)
		(fp_rect
			(start 0.6604 1.1811)
			(end -0.6604 -1.1811)
			(stroke
				(width 0)
				(type default)
			)
			(fill no)
			(layer "B.Fab")
		)
		(pad "A" smd rect
			(at 0 -0.652526 270)
			(size 1.0668 0.8128)
			(layers "B.Cu" "B.Mask" "B.Paste")
			(net "PORT80_R_BIT7")
		)
		(pad "K" smd rect
			(at 0 0.652526 270)
			(size 1.0668 0.8128)
			(layers "B.Cu" "B.Mask" "B.Paste")
			(net "PORT80_BIT7")
		)
	)
	(footprint ""
		(layer "B.Cu")
		(at 30.41904 -48.620426 90)
		(property "Reference" "PU14"
			(at 0 0 90)
			(layer "B.SilkS")
			(hide yes)
			(effects
				(font
					(size 1.27 1.27)
				)
				(justify mirror)
			)
		)
		(property "Value" "TPS74801RGW-GP"
			(at 3.7084 -0.127 90)
			(unlocked yes)
			(layer "B.Fab")
			(hide yes)
			(effects
				(font
					(size 1.016 1.016)
					(thickness 0.1524)
				)
				(justify mirror)
			)
		)
		(property "Device Type" "QFN20-1G3D15H40"
			(at 3.7084 -1.651 90)
			(unlocked yes)
			(layer "B.Fab")
			(hide yes)
			(effects
				(font
					(size 1.016 1.016)
					(thickness 0.1524)
				)
				(justify mirror)
			)
		)
		(duplicate_pad_numbers_are_jumpers no)
		(fp_poly
			(pts
				(xy -1.3208 -2.884932) (xy -1.941068 -3.5052) (xy -0.700786 -3.5052)
			)
			(stroke
				(width 0)
				(type default)
			)
			(fill yes)
			(layer "B.SilkS")
		)
		(fp_rect
			(start 2.8829 2.8829)
			(end -2.8829 -2.8829)
			(stroke
				(width 0)
				(type default)
			)
			(fill no)
			(layer "B.CrtYd")
		)
		(fp_rect
			(start 2.8829 2.8829)
			(end -2.8829 -2.8829)
			(stroke
				(width 0)
				(type default)
			)
			(fill no)
			(layer "B.Fab")
		)
		(pad "1" smd rect
			(at -1.299972 -2.347722 270)
			(size 0.3556 0.8128)
			(layers "B.Cu" "B.Mask" "B.Paste")
			(net "P1V5_STBY_OUT")
		)
		(pad "2" smd rect
			(at -0.649986 -2.347722 270)
			(size 0.3556 0.8128)
			(layers "B.Cu" "B.Mask" "B.Paste")
			(net "GND")
		)
		(pad "3" smd rect
			(at 0 -2.347722 270)
			(size 0.3556 0.8128)
			(layers "B.Cu" "B.Mask" "B.Paste")
			(net "GND")
		)
		(pad "4" smd rect
			(at 0.649986 -2.347722 270)
			(size 0.3556 0.8128)
			(layers "B.Cu" "B.Mask" "B.Paste")
			(net "GND")
		)
		(pad "5" smd rect
			(at 1.299972 -2.347722 270)
			(size 0.3556 0.8128)
			(layers "B.Cu" "B.Mask" "B.Paste")
			(net "P1V5_STBY_IN")
		)
		(pad "6" smd rect
			(at 2.347722 -1.299972 270)
			(size 0.8128 0.3556)
			(layers "B.Cu" "B.Mask" "B.Paste")
			(net "P1V5_STBY_IN")
		)
		(pad "7" smd rect
			(at 2.347722 -0.649986 270)
			(size 0.8128 0.3556)
			(layers "B.Cu" "B.Mask" "B.Paste")
			(net "P1V5_STBY_IN")
		)
		(pad "8" smd rect
			(at 2.347722 0 270)
			(size 0.8128 0.3556)
			(layers "B.Cu" "B.Mask" "B.Paste")
			(net "P1V5_STBY_IN")
		)
		(pad "9" smd rect
			(at 2.347722 0.649986 270)
			(size 0.8128 0.3556)
			(layers "B.Cu" "B.Mask" "B.Paste")
			(net "P1V5_STBY_PG")
		)
		(pad "10" smd rect
			(at 2.347722 1.299972 270)
			(size 0.8128 0.3556)
			(layers "B.Cu" "B.Mask" "B.Paste")
			(net "P1V5_STBY_BIAS")
		)
		(pad "11" smd rect
			(at 1.299972 2.347722 270)
			(size 0.3556 0.8128)
			(layers "B.Cu" "B.Mask" "B.Paste")
			(net "P1V5_STBY_EN")
		)
		(pad "12" smd rect
			(at 0.649986 2.347722 270)
			(size 0.3556 0.8128)
			(layers "B.Cu" "B.Mask" "B.Paste")
			(net "GND")
		)
		(pad "13" smd rect
			(at 0 2.347722 270)
			(size 0.3556 0.8128)
			(layers "B.Cu" "B.Mask" "B.Paste")
			(net "GND")
		)
		(pad "14" smd rect
			(at -0.649986 2.347722 270)
			(size 0.3556 0.8128)
			(layers "B.Cu" "B.Mask" "B.Paste")
			(net "GND")
		)
		(pad "15" smd rect
			(at -1.299972 2.347722 270)
			(size 0.3556 0.8128)
			(layers "B.Cu" "B.Mask" "B.Paste")
			(net "P1V5_STBY_SS")
		)
		(pad "16" smd rect
			(at -2.347722 1.299972 270)
			(size 0.8128 0.3556)
			(layers "B.Cu" "B.Mask" "B.Paste")
			(net "P1V5_STBY_FB")
		)
		(pad "17" smd rect
			(at -2.347722 0.649986 270)
			(size 0.8128 0.3556)
			(layers "B.Cu" "B.Mask" "B.Paste")
			(net "GND")
		)
		(pad "18" smd rect
			(at -2.347722 0 270)
			(size 0.8128 0.3556)
			(layers "B.Cu" "B.Mask" "B.Paste")
			(net "P1V5_STBY_OUT")
		)
		(pad "19" smd rect
			(at -2.347722 -0.649986 270)
			(size 0.8128 0.3556)
			(layers "B.Cu" "B.Mask" "B.Paste")
			(net "P1V5_STBY_OUT")
		)
		(pad "20" smd rect
			(at -2.347722 -1.299972 270)
			(size 0.8128 0.3556)
			(layers "B.Cu" "B.Mask" "B.Paste")
			(net "P1V5_STBY_OUT")
		)
		(pad "21" smd rect
			(at 0 0 270)
			(size 3.2512 3.2512)
			(layers "B.Cu" "B.Mask" "B.Paste")
			(net "GND")
		)
	)
	(footprint ""
		(layer "B.Cu")
		(at 99.187 -45.2882 -90)
		(property "Reference" "L4"
			(at 0 0 90)
			(layer "B.SilkS")
			(hide yes)
			(effects
				(font
					(size 1.27 1.27)
				)
				(justify mirror)
			)
		)
		(property "Value" "BLM18PG121SN1D-GP"
			(at 0.0254 -2.8956 270)
			(unlocked yes)
			(layer "B.Fab")
			(hide yes)
			(effects
				(font
					(size 1.016 1.016)
					(thickness 0.1524)
				)
				(justify mirror)
			)
		)
		(property "Device Type" "L1608-UH38"
			(at 0.0254 -4.4196 270)
			(unlocked yes)
			(layer "B.Fab")
			(hide yes)
			(effects
				(font
					(size 1.016 1.016)
					(thickness 0.1524)
				)
				(justify mirror)
			)
		)
		(duplicate_pad_numbers_are_jumpers no)
		(fp_line
			(start 0.4064 0)
			(end -0.4064 0)
			(stroke
				(width 0.2032)
				(type default)
			)
			(layer "B.SilkS")
		)
		(fp_rect
			(start 0.635 1.1811)
			(end -0.635 -1.1811)
			(stroke
				(width 0)
				(type default)
			)
			(fill no)
			(layer "B.CrtYd")
		)
		(fp_rect
			(start 0.635 1.1811)
			(end -0.635 -1.1811)
			(stroke
				(width 0)
				(type default)
			)
			(fill no)
			(layer "B.Fab")
		)
		(pad "1" smd custom
			(at 0 -0.6604 90)
			(size 0.19685 0.19685)
			(layers "B.Cu" "B.Mask" "B.Paste")
			(net "PV_VDDR")
			(options
				(clearance outline)
				(anchor circle)
			)
			(primitives
				(gr_poly
					(pts
						(arc
							(start 0.508 0.2921)
							(mid 0.478242 0.363942)
							(end 0.4064 0.3937)
						)
						(arc
							(start -0.4064 0.3937)
							(mid -0.478242 0.363942)
							(end -0.508 0.2921)
						)
						(arc
							(start -0.508 -0.2921)
							(mid -0.478242 -0.363942)
							(end -0.4064 -0.3937)
						)
						(arc
							(start 0.4064 -0.3937)
							(mid 0.478242 -0.363942)
							(end 0.508 -0.2921)
						)
					)
					(width 0)
					(fill yes)
				)
			)
		)
		(pad "2" smd custom
			(at 0 0.6604 90)
			(size 0.19685 0.19685)
			(layers "B.Cu" "B.Mask" "B.Paste")
			(net "VCCCLKDDR0")
			(options
				(clearance outline)
				(anchor circle)
			)
			(primitives
				(gr_poly
					(pts
						(arc
							(start 0.508 0.2921)
							(mid 0.478242 0.363942)
							(end 0.4064 0.3937)
						)
						(arc
							(start -0.4064 0.3937)
							(mid -0.478242 0.363942)
							(end -0.508 0.2921)
						)
						(arc
							(start -0.508 -0.2921)
							(mid -0.478242 -0.363942)
							(end -0.4064 -0.3937)
						)
						(arc
							(start 0.4064 -0.3937)
							(mid 0.478242 -0.363942)
							(end 0.508 -0.2921)
						)
					)
					(width 0)
					(fill yes)
				)
			)
		)
	)
	(footprint ""
		(layer "B.Cu")
		(at 51.816 -58.547 90)
		(property "Reference" "PR89"
			(at 0 0 90)
			(layer "B.SilkS")
			(hide yes)
			(effects
				(font
					(size 1.27 1.27)
				)
				(justify mirror)
			)
		)
		(property "Value" "0R2J-2-GP"
			(at -0.064008 -3.993896 90)
			(unlocked yes)
			(layer "B.Fab")
			(hide yes)
			(effects
				(font
					(size 1.016 1.016)
					(thickness 0.1524)
				)
				(justify mirror)
			)
		)
		(property "Device Type" "R402H16"
			(at -0.064008 -5.517896 90)
			(unlocked yes)
			(layer "B.Fab")
			(hide yes)
			(effects
				(font
					(size 1.016 1.016)
					(thickness 0.1524)
				)
				(justify mirror)
			)
		)
		(duplicate_pad_numbers_are_jumpers no)
		(fp_rect
			(start 0.381 0.8382)
			(end -0.381 -0.8382)
			(stroke
				(width 0)
				(type default)
			)
			(fill no)
			(layer "B.CrtYd")
		)
		(fp_rect
			(start 0.381 0.8382)
			(end -0.381 -0.8382)
			(stroke
				(width 0)
				(type default)
			)
			(fill no)
			(layer "B.Fab")
		)
		(pad "1" smd custom
			(at 0 -0.4318 270)
			(size 0.127 0.127)
			(layers "B.Cu" "B.Mask" "B.Paste")
			(net "VR_PVCCP_ISUMN_R2")
			(options
				(clearance outline)
				(anchor circle)
			)
			(primitives
				(gr_poly
					(pts
						(arc
							(start -0.2032 0.2794)
							(mid -0.239121 0.264521)
							(end -0.254 0.2286)
						)
						(arc
							(start -0.254 -0.2286)
							(mid -0.239121 -0.264521)
							(end -0.2032 -0.2794)
						)
						(arc
							(start 0.2032 -0.2794)
							(mid 0.239121 -0.264521)
							(end 0.254 -0.2286)
						)
						(arc
							(start 0.254 0.2286)
							(mid 0.239121 0.264521)
							(end 0.2032 0.2794)
						)
					)
					(width 0)
					(fill yes)
				)
			)
		)
		(pad "2" smd custom
			(at 0 0.4318 270)
			(size 0.127 0.127)
			(layers "B.Cu" "B.Mask" "B.Paste")
			(net "PVCCP")
			(options
				(clearance outline)
				(anchor circle)
			)
			(primitives
				(gr_poly
					(pts
						(arc
							(start -0.2032 0.2794)
							(mid -0.239121 0.264521)
							(end -0.254 0.2286)
						)
						(arc
							(start -0.254 -0.2286)
							(mid -0.239121 -0.264521)
							(end -0.2032 -0.2794)
						)
						(arc
							(start 0.2032 -0.2794)
							(mid 0.239121 -0.264521)
							(end 0.254 -0.2286)
						)
						(arc
							(start 0.254 0.2286)
							(mid 0.239121 0.264521)
							(end 0.2032 0.2794)
						)
					)
					(width 0)
					(fill yes)
				)
			)
		)
	)
	(footprint ""
		(layer "B.Cu")
		(at 189.865 -16.383 180)
		(property "Reference" "C289"
			(at 0 0 0)
			(layer "B.SilkS")
			(hide yes)
			(effects
				(font
					(size 1.27 1.27)
				)
				(justify mirror)
			)
		)
		(property "Value" "SC10U6D3V3MX-GP"
			(at 0 -2.8194 180)
			(unlocked yes)
			(layer "B.Fab")
			(hide yes)
			(effects
				(font
					(size 1.016 1.016)
					(thickness 0.1524)
				)
				(justify mirror)
			)
		)
		(property "Device Type" "C603H38"
			(at 0 -4.3434 180)
			(unlocked yes)
			(layer "B.Fab")
			(hide yes)
			(effects
				(font
					(size 1.016 1.016)
					(thickness 0.1524)
				)
				(justify mirror)
			)
		)
		(duplicate_pad_numbers_are_jumpers no)
		(fp_line
			(start 0.4064 0)
			(end -0.4064 0)
			(stroke
				(width 0.2286)
				(type default)
			)
			(layer "B.SilkS")
		)
		(fp_rect
			(start 0.635 1.1811)
			(end -0.635 -1.1811)
			(stroke
				(width 0)
				(type default)
			)
			(fill no)
			(layer "B.CrtYd")
		)
		(fp_rect
			(start 0.635 1.1811)
			(end -0.635 -1.1811)
			(stroke
				(width 0)
				(type default)
			)
			(fill no)
			(layer "B.Fab")
		)
		(pad "1" smd custom
			(at 0 -0.6604)
			(size 0.19685 0.19685)
			(layers "B.Cu" "B.Mask" "B.Paste")
			(net "PV_VTT_DDR_B")
			(options
				(clearance outline)
				(anchor circle)
			)
			(primitives
				(gr_poly
					(pts
						(arc
							(start 0.508 0.2921)
							(mid 0.478242 0.363942)
							(end 0.4064 0.3937)
						)
						(arc
							(start -0.4064 0.3937)
							(mid -0.478242 0.363942)
							(end -0.508 0.2921)
						)
						(arc
							(start -0.508 -0.2921)
							(mid -0.478242 -0.363942)
							(end -0.4064 -0.3937)
						)
						(arc
							(start 0.4064 -0.3937)
							(mid 0.478242 -0.363942)
							(end 0.508 -0.2921)
						)
					)
					(width 0)
					(fill yes)
				)
			)
		)
		(pad "2" smd custom
			(at 0 0.6604)
			(size 0.19685 0.19685)
			(layers "B.Cu" "B.Mask" "B.Paste")
			(net "GND")
			(options
				(clearance outline)
				(anchor circle)
			)
			(primitives
				(gr_poly
					(pts
						(arc
							(start 0.508 0.2921)
							(mid 0.478242 0.363942)
							(end 0.4064 0.3937)
						)
						(arc
							(start -0.4064 0.3937)
							(mid -0.478242 0.363942)
							(end -0.508 0.2921)
						)
						(arc
							(start -0.508 -0.2921)
							(mid -0.478242 -0.363942)
							(end -0.4064 -0.3937)
						)
						(arc
							(start 0.4064 -0.3937)
							(mid 0.478242 -0.363942)
							(end 0.508 -0.2921)
						)
					)
					(width 0)
					(fill yes)
				)
			)
		)
	)
	(footprint ""
		(layer "B.Cu")
		(at 146.431 -44.958 180)
		(property "Reference" "R130"
			(at 0 0 0)
			(layer "B.SilkS")
			(hide yes)
			(effects
				(font
					(size 1.27 1.27)
				)
				(justify mirror)
			)
		)
		(property "Value" "10KR2F-2-GP"
			(at -0.064008 -3.993896 180)
			(unlocked yes)
			(layer "B.Fab")
			(hide yes)
			(effects
				(font
					(size 1.016 1.016)
					(thickness 0.1524)
				)
				(justify mirror)
			)
		)
		(property "Device Type" "R402H16"
			(at -0.064008 -5.517896 180)
			(unlocked yes)
			(layer "B.Fab")
			(hide yes)
			(effects
				(font
					(size 1.016 1.016)
					(thickness 0.1524)
				)
				(justify mirror)
			)
		)
		(duplicate_pad_numbers_are_jumpers no)
		(fp_rect
			(start 0.381 0.8382)
			(end -0.381 -0.8382)
			(stroke
				(width 0)
				(type default)
			)
			(fill no)
			(layer "B.CrtYd")
		)
		(fp_rect
			(start 0.381 0.8382)
			(end -0.381 -0.8382)
			(stroke
				(width 0)
				(type default)
			)
			(fill no)
			(layer "B.Fab")
		)
		(pad "1" smd custom
			(at 0 -0.4318)
			(size 0.127 0.127)
			(layers "B.Cu" "B.Mask" "B.Paste")
			(net "P3V3_STBY")
			(options
				(clearance outline)
				(anchor circle)
			)
			(primitives
				(gr_poly
					(pts
						(arc
							(start -0.2032 0.2794)
							(mid -0.239121 0.264521)
							(end -0.254 0.2286)
						)
						(arc
							(start -0.254 -0.2286)
							(mid -0.239121 -0.264521)
							(end -0.2032 -0.2794)
						)
						(arc
							(start 0.2032 -0.2794)
							(mid 0.239121 -0.264521)
							(end 0.254 -0.2286)
						)
						(arc
							(start 0.254 0.2286)
							(mid 0.239121 0.264521)
							(end 0.2032 0.2794)
						)
					)
					(width 0)
					(fill yes)
				)
			)
		)
		(pad "2" smd custom
			(at 0 0.4318)
			(size 0.127 0.127)
			(layers "B.Cu" "B.Mask" "B.Paste")
			(net "C_NSTATUS#")
			(options
				(clearance outline)
				(anchor circle)
			)
			(primitives
				(gr_poly
					(pts
						(arc
							(start -0.2032 0.2794)
							(mid -0.239121 0.264521)
							(end -0.254 0.2286)
						)
						(arc
							(start -0.254 -0.2286)
							(mid -0.239121 -0.264521)
							(end -0.2032 -0.2794)
						)
						(arc
							(start 0.2032 -0.2794)
							(mid 0.239121 -0.264521)
							(end 0.254 -0.2286)
						)
						(arc
							(start 0.254 0.2286)
							(mid 0.239121 0.264521)
							(end 0.2032 0.2794)
						)
					)
					(width 0)
					(fill yes)
				)
			)
		)
	)
)
